# BASEBOARD_FAB2 (Tioga Pass) — schematic netlist excerpt (pin names and nets, part order shuffled) for the footprints in the layout excerpt that follows; sources: Cadence DE-HDL packaged netlist, KiCad conversion of Wiwynn_Tioga_Pass_MB.brd

C835  CAP  0.22UF 16V 10% X7R  pkg 0402  page 244 : A = P3E_CPU0_PE1_PCH_TXP<10> ; B = P3E_CPU0_PE1_PCH_CON_TXP<10>

U1B2  TCA9517DGKR-GP  pkg DISCRET-G8  page 163
  VCCA  = PVCCIO_CPU1
  SCLA  = SMB_CPU1_PE_HP_GTL_R_SCL
  SDAA  = SMB_CPU1_PE_HP_GTL_R_SDA
  GND  = GND
  EN  = TP_SMB_PEHPCPU1_EN
  SDAB  = SMB_PEHPCPU1_STBY_LVC3_R_SDA
  SCLB  = SMB_PEHPCPU1_STBY_LVC3_R_SCL
  VCCB  = P3V3_STBY

(kicad_pcb
	(version 20260206)
	(generator "pcbnew")
	(generator_version "10.0")
	(general
		(thickness 1.6)
		(legacy_teardrops no)
	)
	(paper "A4")
	(title_block
		(title "Wiwynn_Tioga_Pass_MB.brd")
		(comment 1 "Tioga Pass / footprints 1302-1303 of 4770")
	)
	(layers
		(0 "F.Cu" signal "TOP")
		(4 "In1.Cu" signal "L2GND")
		(6 "In2.Cu" signal "L3")
		(8 "In3.Cu" signal "L4GND")
		(10 "In4.Cu" signal "L5")
		(12 "In5.Cu" signal "L6GND")
		(14 "In6.Cu" signal "L7VCC")
		(16 "In7.Cu" signal "L8VCC")
		(18 "In8.Cu" signal "L9GND")
		(20 "In9.Cu" signal "L10")
		(22 "In10.Cu" signal "L11GND")
		(24 "In11.Cu" signal "L12")
		(26 "In12.Cu" signal "L13GND")
		(2 "B.Cu" signal "BOTTOM")
		(9 "F.Adhes" user "F.Adhesive")
		(11 "B.Adhes" user "B.Adhesive")
		(13 "F.Paste" user "Package Geometry/Pastemask Top")
		(15 "B.Paste" user "Package Geometry/Pastemask Bottom")
		(5 "F.SilkS" user "Ref Des/Silkscreen Top")
		(7 "B.SilkS" user "Ref Des/Silkscreen Bottom")
		(1 "F.Mask" user "Board Geometry/Soldermask Top")
		(3 "B.Mask" user "Board Geometry/Soldermask Bottom")
		(17 "Dwgs.User" user "User.Drawings")
		(19 "Cmts.User" user "User.Comments")
		(21 "Eco1.User" user "User.Eco1")
		(23 "Eco2.User" user "User.Eco2")
		(25 "Edge.Cuts" user "Board Geometry/Outline")
		(27 "Margin" user)
		(31 "F.CrtYd" user "Package Geometry/Place Bound Top")
		(29 "B.CrtYd" user "Package Geometry/Place Bound Bottom")
		(35 "F.Fab" user "Ref Des/Assembly Top")
		(33 "B.Fab" user "Ref Des/Assembly Bottom")
	)
	(footprint ""
		(layer "F.Cu")
		(at -3.180588 -119.4435)
		(property "Reference" "U1B2"
			(at 0 0 0)
			(layer "F.SilkS")
			(hide yes)
			(effects
				(font
					(size 1.27 1.27)
				)
			)
		)
		(property "Value" "*"
			(at -0.1143 -9.3091 0)
			(unlocked yes)
			(layer "F.Fab")
			(hide yes)
			(effects
				(font
					(size 1.27 1.016)
					(thickness 0.1524)
				)
			)
		)
		(property "Device Type" "TCA9517DGKR-GP_DISCRET-G8-TCA9A"
			(at -0.1143 -10.9093 0)
			(unlocked yes)
			(layer "F.Fab")
			(hide yes)
			(effects
				(font
					(size 1.27 1.016)
					(thickness 0.1524)
				)
			)
		)
		(duplicate_pad_numbers_are_jumpers no)
		(fp_line
			(start -1.9558 -1.016)
			(end -1.9558 1.016)
			(stroke
				(width 0.1524)
				(type default)
			)
			(layer "F.SilkS")
		)
		(fp_line
			(start -1.9558 -0.5461)
			(end -1.4478 -0.0381)
			(stroke
				(width 0.1524)
				(type default)
			)
			(layer "F.SilkS")
		)
		(fp_line
			(start -1.9558 1.016)
			(end 1.0795 1.016)
			(stroke
				(width 0.1524)
				(type default)
			)
			(layer "F.SilkS")
		)
		(fp_line
			(start -1.778 1.0922)
			(end -1.778 3.048)
			(stroke
				(width 0.508)
				(type default)
			)
			(layer "F.SilkS")
		)
		(fp_line
			(start -1.4478 -0.0381)
			(end -1.9558 0.4699)
			(stroke
				(width 0.1524)
				(type default)
			)
			(layer "F.SilkS")
		)
		(fp_line
			(start 1.0795 -1.016)
			(end -1.9558 -1.016)
			(stroke
				(width 0.1524)
				(type default)
			)
			(layer "F.SilkS")
		)
		(fp_line
			(start 1.0795 1.016)
			(end 1.0795 -1.016)
			(stroke
				(width 0.1524)
				(type default)
			)
			(layer "F.SilkS")
		)
		(fp_poly
			(pts
				(xy -1.1557 -1.016) (xy -1.1557 1.016) (xy 1.1557 1.016) (xy 1.1557 -1.016)
			)
			(stroke
				(width 0)
				(type default)
			)
			(fill yes)
			(layer "F.SilkS")
		)
		(fp_rect
			(start -1.4986 2.4511)
			(end 1.4986 -2.4511)
			(stroke
				(width 0)
				(type default)
			)
			(fill no)
			(layer "F.CrtYd")
		)
		(fp_poly
			(pts
				(xy -2.032 3.302) (xy -2.032 -3.302) (xy 2.032 -3.302) (xy 2.032 -2.1209) (xy 1.4986 -2.1209) (xy 1.4986 -2.4511)
				(xy -1.4986 -2.4511) (xy -1.4986 2.4511) (xy 1.4986 2.4511) (xy 1.4986 -2.1082) (xy 2.032 -2.1082)
				(xy 2.032 3.302)
			)
			(stroke
				(width 0)
				(type default)
			)
			(fill no)
			(layer "F.CrtYd")
		)
		(fp_rect
			(start -2.032 3.302)
			(end 2.032 -3.302)
			(stroke
				(width 0)
				(type default)
			)
			(fill no)
			(layer "F.Fab")
		)
		(pad "1" smd rect
			(at -0.97536 2.05486)
			(size 0.3556 1.524)
			(layers "F.Cu" "F.Mask" "F.Paste")
			(net "PVCCIO_CPU1")
		)
		(pad "2" smd rect
			(at -0.32512 2.05486)
			(size 0.3556 1.524)
			(layers "F.Cu" "F.Mask" "F.Paste")
			(net "SMB_CPU1_PE_HP_GTL_R_SCL")
		)
		(pad "3" smd rect
			(at 0.32512 2.05486)
			(size 0.3556 1.524)
			(layers "F.Cu" "F.Mask" "F.Paste")
			(net "SMB_CPU1_PE_HP_GTL_R_SDA")
		)
		(pad "4" smd rect
			(at 0.97536 2.05486)
			(size 0.3556 1.524)
			(layers "F.Cu" "F.Mask" "F.Paste")
			(net "GND")
		)
		(pad "5" smd rect
			(at 0.97536 -2.05486)
			(size 0.3556 1.524)
			(layers "F.Cu" "F.Mask" "F.Paste")
			(net "TP_SMB_PEHPCPU1_EN")
		)
		(pad "6" smd rect
			(at 0.32512 -2.05486)
			(size 0.3556 1.524)
			(layers "F.Cu" "F.Mask" "F.Paste")
			(net "SMB_PEHPCPU1_STBY_LVC3_R_SDA")
		)
		(pad "7" smd rect
			(at -0.32512 -2.05486)
			(size 0.3556 1.524)
			(layers "F.Cu" "F.Mask" "F.Paste")
			(net "SMB_PEHPCPU1_STBY_LVC3_R_SCL")
		)
		(pad "8" smd rect
			(at -0.97536 -2.05486)
			(size 0.3556 1.524)
			(layers "F.Cu" "F.Mask" "F.Paste")
			(net "P3V3_STBY")
		)
	)
	(footprint ""
		(layer "F.Cu")
		(at 337.429602 -120.038368 -90)
		(property "Reference" "C835"
			(at -0.8382 -0.67818 270)
			(unlocked yes)
			(layer "F.SilkS")
			(effects
				(font
					(size 0.4064 0.254)
					(thickness 0.1524)
				)
				(justify left)
			)
		)
		(property "Value" ""
			(at 0 0 270)
			(layer "F.Fab")
			(effects
				(font
					(size 1.27 1.27)
				)
			)
		)
		(duplicate_pad_numbers_are_jumpers no)
		(fp_poly
			(pts
				(xy 0.3048 -0.1016) (xy 0.3048 0.9906) (xy -0.3048 0.9906) (xy -0.3048 -0.1016)
			)
			(stroke
				(width 0)
				(type default)
			)
			(fill no)
			(layer "F.CrtYd")
		)
		(fp_line
			(start -0.3048 0.9906)
			(end 0.3048 0.9906)
			(stroke
				(width 0.1)
				(type default)
			)
			(layer "F.Fab")
		)
		(fp_line
			(start 0.3048 0.9906)
			(end 0.3048 -0.1016)
			(stroke
				(width 0.1)
				(type default)
			)
			(layer "F.Fab")
		)
		(fp_line
			(start -0.3048 -0.1016)
			(end -0.3048 0.9906)
			(stroke
				(width 0.1)
				(type default)
			)
			(layer "F.Fab")
		)
		(fp_line
			(start 0.3048 -0.1016)
			(end -0.3048 -0.1016)
			(stroke
				(width 0.1)
				(type default)
			)
			(layer "F.Fab")
		)
		(pad "1" smd rect
			(at 0 0 270)
			(size 0.508 0.508)
			(layers "F.Cu" "F.Mask" "F.Paste")
			(net "P3E_CPU0_PE1_PCH_TXP<10>")
		)
		(pad "2" smd rect
			(at 0 0.889 270)
			(size 0.508 0.508)
			(layers "F.Cu" "F.Mask" "F.Paste")
			(net "P3E_CPU0_PE1_PCH_CON_TXP<10>")
		)
		(zone
			(layer "F.Cu")
			(hatch none 0.5)
			(connect_pads
				(clearance 0)
			)
			(min_thickness 0.25)
			(keepout
				(tracks not_allowed)
				(vias allowed)
				(pads allowed)
				(copperpour not_allowed)
				(footprints allowed)
			)
			(placement
				(enabled no)
				(sheetname "")
			)
			(fill
				(thermal_gap 0.5)
				(thermal_bridge_width 0.5)
				(island_removal_mode 0)
			)
			(polygon
				(pts
					(xy 336.794602 -120.292368) (xy 336.794602 -119.784368) (xy 337.175602 -119.784368) (xy 337.175602 -120.292368)
				)
			)
		)
		(zone
			(layer "F.Cu")
			(hatch none 0.5)
			(connect_pads
				(clearance 0)
			)
			(min_thickness 0.25)
			(keepout
				(tracks allowed)
				(vias not_allowed)
				(pads allowed)
				(copperpour not_allowed)
				(footprints allowed)
			)
			(placement
				(enabled no)
				(sheetname "")
			)
			(fill
				(thermal_gap 0.5)
				(thermal_bridge_width 0.5)
				(island_removal_mode 0)
			)
			(polygon
				(pts
					(xy 337.175602 -120.292368) (xy 337.175602 -119.784368) (xy 336.794602 -119.784368) (xy 336.794602 -120.292368)
				)
			)
		)
	)
)
